(kicad_pcb
	(version 20221018)
	(generator pcbnew)
	(general
    (thickness 1.562)
  )
	(paper "A4")
	(title_block
    (title "Thunderbolt PCIe Adaper")
    (date "2024-07-09")
    (rev "1.0.3")
    (comment 1 "www.antmicro.com")
    (comment 2 "Antmicro Ltd.")
		(comment 9 "footprints 186-193 of 271")
	)
	(layers
    (0 "F.Cu" signal)
    (1 "In1.Cu" signal)
    (2 "In2.Cu" signal)
    (3 "In3.Cu" signal)
    (4 "In4.Cu" signal)
    (31 "B.Cu" signal)
    (32 "B.Adhes" user "B.Adhesive")
    (33 "F.Adhes" user "F.Adhesive")
    (34 "B.Paste" user)
    (35 "F.Paste" user)
    (36 "B.SilkS" user "B.Silkscreen")
    (37 "F.SilkS" user "F.Silkscreen")
    (38 "B.Mask" user)
    (39 "F.Mask" user)
    (40 "Dwgs.User" user "User.Drawings")
    (41 "Cmts.User" user "User.Comments")
    (42 "Eco1.User" user "User.Eco1")
    (43 "Eco2.User" user "User.Eco2")
    (44 "Edge.Cuts" user)
    (45 "Margin" user)
    (46 "B.CrtYd" user "B.Courtyard")
    (47 "F.CrtYd" user "F.Courtyard")
    (48 "B.Fab" user)
    (49 "F.Fab" user)
  )
	(footprint "antmicro-footprints:R_0402_1005Metric" (layer "B.Cu")
    (at 116.920001 60.195)
    (descr "Resistor SMD 0402")
    (tags "resistor SMD 0402")
    (property "Author" "Antmicro")
    (property "License" "Apache-2.0")
    (property "MPN" "CR0402-FX-4022GLF")
    (property "Manufacturer" "Bourns")
    (property "Sheetfile" "power.kicad_sch")
    (property "Sheetname" "Power")
    (property "Tolerance" "1%")
    (property "Val" "40k2")
    (property "ki_description" "SMD Chip Resistor, 40.2 kohm, ± 1%, 63 mW, 0402 [1005 Metric], Thick Film, General Purpose")
    (property "ki_keywords" "0402, SMT, RESISTOR, PASSIVE")
    (attr smd)
    (fp_text reference "R36" (at 3.094999 0.384 180) (layer "B.SilkS")
        (effects (font (size 0.7 0.7) (thickness 0.15)) (justify left bottom mirror))
    )
    (fp_text value "R_40k2_0402" (at -1.011843 -1.772047 180) (layer "B.Fab")
        (effects (font (size 0.7 0.7) (thickness 0.15)) (justify left bottom mirror))
    )
    (fp_text user "License: Apache-2.0" (at -0.95 -5.169 180) (layer "B.Fab") hide
        (effects (font (size 0.7 0.7) (thickness 0.15)) (justify left bottom mirror))
    )
    (fp_text user "${REFERENCE}" (at -0.95 -3.168 180) (layer "B.Fab") hide
        (effects (font (size 0.7 0.7) (thickness 0.15)) (justify left bottom mirror))
    )
    (fp_text user "Author: Antmicro" (at -0.95 -4.169 180) (layer "B.Fab") hide
        (effects (font (size 0.7 0.7) (thickness 0.15)) (justify left bottom mirror))
    )
    (fp_rect (start -0.925 0.47) (end 0.925 -0.47)
      (stroke (width 0.05) (type default)) (fill none) (layer "B.CrtYd"))
    (fp_rect (start -0.5 0.25) (end 0.5 -0.25)
      (stroke (width 0.15) (type solid)) (fill none) (layer "B.Fab"))
    (pad "1" smd roundrect (at -0.48 0) (size 0.59 0.64) (layers "B.Cu" "B.Paste" "B.Mask") (roundrect_rratio 0.25)
      (net 99 "Net-(U2-FB)") (pintype "passive"))
    (pad "2" smd roundrect (at 0.48 0) (size 0.59 0.64) (layers "B.Cu" "B.Paste" "B.Mask") (roundrect_rratio 0.25)
      (net 100 "Net-(D2-A)") (pintype "passive"))
  )
	(footprint "antmicro-footprints:R_0402_1005Metric" (layer "B.Cu")
    (at 130.05 70.72 -90)
    (descr "Resistor SMD 0402")
    (tags "resistor SMD 0402")
    (property "Author" "Antmicro")
    (property "License" "Apache-2.0")
    (property "MPN" "CR0402-FX-1003GLF")
    (property "Manufacturer" "Bourns")
    (property "Sheetfile" "tb.kicad_sch")
    (property "Sheetname" "TB Controller")
    (property "Tolerance" "1%")
    (property "Val" "100k")
    (property "ki_description" "SMD Chip Resistor, 100 kohm, ± 1%, 62.5 mW, 0402 [1005 Metric], Thick Film, General Purpose")
    (property "ki_keywords" "0402, SMT, RESISTOR, PASSIVE")
    (attr smd)
    (fp_text reference "R57" (at 0.908 -0.379 90) (layer "B.SilkS")
        (effects (font (size 0.7 0.7) (thickness 0.15)) (justify left bottom mirror))
    )
    (fp_text value "R_100k_0402" (at -1.011843 -1.772047 90) (layer "B.Fab")
        (effects (font (size 0.7 0.7) (thickness 0.15)) (justify left bottom mirror))
    )
    (fp_text user "Author: Antmicro" (at -0.95 -4.169 90) (layer "B.Fab") hide
        (effects (font (size 0.7 0.7) (thickness 0.15)) (justify left bottom mirror))
    )
    (fp_text user "${REFERENCE}" (at -0.95 -3.168 90) (layer "B.Fab") hide
        (effects (font (size 0.7 0.7) (thickness 0.15)) (justify left bottom mirror))
    )
    (fp_text user "License: Apache-2.0" (at -0.95 -5.169 90) (layer "B.Fab") hide
        (effects (font (size 0.7 0.7) (thickness 0.15)) (justify left bottom mirror))
    )
    (fp_rect (start -0.925 0.47) (end 0.925 -0.47)
      (stroke (width 0.05) (type default)) (fill none) (layer "B.CrtYd"))
    (fp_rect (start -0.5 0.25) (end 0.5 -0.25)
      (stroke (width 0.15) (type solid)) (fill none) (layer "B.Fab"))
    (pad "1" smd roundrect (at -0.48 0 270) (size 0.59 0.64) (layers "B.Cu" "B.Paste" "B.Mask") (roundrect_rratio 0.25)
      (net 1 "GND") (pintype "passive"))
    (pad "2" smd roundrect (at 0.48 0 270) (size 0.59 0.64) (layers "B.Cu" "B.Paste" "B.Mask") (roundrect_rratio 0.25)
      (net 171 "Net-(U4C-DPSNK0_HPD)") (pintype "passive"))
  )
	(footprint "antmicro-footprints:C_0402_1005Metric" (layer "B.Cu")
    (at 143.15 74.482 -90)
    (descr "Capacitor SMD 0402")
    (tags "capacitor SMD 0402")
    (property "Author" "Antmicro")
    (property "Dielectric" "")
    (property "License" "Apache-2.0")
    (property "MPN" "CC0402MRX5R5BB106")
    (property "Manufacturer" "YAGEO")
    (property "Sheetfile" "tb-power.kicad_sch")
    (property "Sheetname" "Thunderbolt Controller - Power")
    (property "Val" "10u")
    (property "Voltage" "")
    (property "ki_description" "SMD Multilayer Ceramic Capacitor, 10 µF, 6.3 V, 0402 [1005 Metric], ± 20%, X5R, CC Series")
    (property "ki_keywords" "0402, SMT, CAPACITOR, PASSIVE, MLCC, CERAMIC")
    (attr smd)
    (fp_text reference "C70" (at -5.521 -1.503 90) (layer "B.SilkS")
        (effects (font (size 0.7 0.7) (thickness 0.15)) (justify left bottom mirror))
    )
    (fp_text value "C_10u_0402" (at -1.022927 -2.155213 90) (layer "B.Fab")
        (effects (font (size 0.7 0.7) (thickness 0.15)) (justify left bottom mirror))
    )
    (fp_text user "Author: Antmicro" (at -0.939 -3.399 90) (layer "B.Fab") hide
        (effects (font (size 0.7 0.7) (thickness 0.15)) (justify left bottom mirror))
    )
    (fp_text user "${REFERENCE}" (at -0.939 -4.599 90) (layer "B.Fab") hide
        (effects (font (size 0.7 0.7) (thickness 0.15)) (justify left bottom mirror))
    )
    (fp_text user "License: Apache-2.0" (at -0.939 -5.799 90) (layer "B.Fab") hide
        (effects (font (size 0.7 0.7) (thickness 0.15)) (justify left bottom mirror))
    )
    (fp_rect (start -0.925 0.47) (end 0.925 -0.47)
      (stroke (width 0.05) (type default)) (fill none) (layer "B.CrtYd"))
    (fp_line (start -0.494 -0.248) (end -0.494 0.25)
      (stroke (width 0.15) (type solid)) (layer "B.Fab"))
    (fp_line (start -0.494 0.25) (end 0.504 0.25)
      (stroke (width 0.15) (type solid)) (layer "B.Fab"))
    (fp_line (start 0.504 -0.248) (end -0.494 -0.248)
      (stroke (width 0.15) (type solid)) (layer "B.Fab"))
    (fp_line (start 0.504 0.25) (end 0.504 -0.248)
      (stroke (width 0.15) (type solid)) (layer "B.Fab"))
    (pad "1" smd roundrect (at -0.48 0 270) (size 0.59 0.64) (layers "B.Cu" "B.Paste" "B.Mask") (roundrect_rratio 0.25)
      (net 1 "GND") (pintype "passive"))
    (pad "2" smd roundrect (at 0.48 0 270) (size 0.59 0.64) (layers "B.Cu" "B.Paste" "B.Mask") (roundrect_rratio 0.25)
      (net 2 "3V3_SYS") (pintype "passive"))
  )
	(footprint "antmicro-footprints:C_0402_1005Metric" (layer "B.Cu")
    (at 134.8 79.85)
    (descr "Capacitor SMD 0402")
    (tags "capacitor SMD 0402")
    (property "Author" "Antmicro")
    (property "Dielectric" "")
    (property "License" "Apache-2.0")
    (property "MPN" "C1005X6S1A105K050BC")
    (property "Manufacturer" "TDK")
    (property "Sheetfile" "tb-power.kicad_sch")
    (property "Sheetname" "Thunderbolt Controller - Power")
    (property "Val" "1u")
    (property "Voltage" "")
    (property "ki_description" "SMD Multilayer Ceramic Capacitor, 1 µF, 10 V, 0402 [1005 Metric], ± 10%, X6S, C")
    (property "ki_keywords" "0402, SMT, CAPACITOR, PASSIVE, CERAMIC, MLCC")
    (attr smd)
    (fp_text reference "C67" (at 17.6 7.653 180) (layer "B.SilkS")
        (effects (font (size 0.7 0.7) (thickness 0.15)) (justify left bottom mirror))
    )
    (fp_text value "C_1u_0402" (at -1.022927 -2.155213 180) (layer "B.Fab")
        (effects (font (size 0.7 0.7) (thickness 0.15)) (justify left bottom mirror))
    )
    (fp_text user "${REFERENCE}" (at -0.939 -4.599 180) (layer "B.Fab") hide
        (effects (font (size 0.7 0.7) (thickness 0.15)) (justify left bottom mirror))
    )
    (fp_text user "License: Apache-2.0" (at -0.939 -5.799 180) (layer "B.Fab") hide
        (effects (font (size 0.7 0.7) (thickness 0.15)) (justify left bottom mirror))
    )
    (fp_text user "Author: Antmicro" (at -0.939 -3.399 180) (layer "B.Fab") hide
        (effects (font (size 0.7 0.7) (thickness 0.15)) (justify left bottom mirror))
    )
    (fp_rect (start -0.925 0.47) (end 0.925 -0.47)
      (stroke (width 0.05) (type default)) (fill none) (layer "B.CrtYd"))
    (fp_line (start -0.494 -0.248) (end -0.494 0.25)
      (stroke (width 0.15) (type solid)) (layer "B.Fab"))
    (fp_line (start -0.494 0.25) (end 0.504 0.25)
      (stroke (width 0.15) (type solid)) (layer "B.Fab"))
    (fp_line (start 0.504 -0.248) (end -0.494 -0.248)
      (stroke (width 0.15) (type solid)) (layer "B.Fab"))
    (fp_line (start 0.504 0.25) (end 0.504 -0.248)
      (stroke (width 0.15) (type solid)) (layer "B.Fab"))
    (pad "1" smd roundrect (at -0.48 0) (size 0.59 0.64) (layers "B.Cu" "B.Paste" "B.Mask") (roundrect_rratio 0.25)
      (net 1 "GND") (pintype "passive"))
    (pad "2" smd roundrect (at 0.48 0) (size 0.59 0.64) (layers "B.Cu" "B.Paste" "B.Mask") (roundrect_rratio 0.25)
      (net 106 "Net-(C53-Pad2)") (pintype "passive"))
  )
	(footprint "antmicro-footprints:C_0402_1005Metric" (layer "B.Cu")
    (at 130.9 78.875)
    (descr "Capacitor SMD 0402")
    (tags "capacitor SMD 0402")
    (property "Author" "Antmicro")
    (property "Dielectric" "")
    (property "License" "Apache-2.0")
    (property "MPN" "C1005X6S1A105K050BC")
    (property "Manufacturer" "TDK")
    (property "Sheetfile" "tb-power.kicad_sch")
    (property "Sheetname" "Thunderbolt Controller - Power")
    (property "Val" "1u")
    (property "Voltage" "")
    (property "ki_description" "SMD Multilayer Ceramic Capacitor, 1 µF, 10 V, 0402 [1005 Metric], ± 10%, X6S, C")
    (property "ki_keywords" "0402, SMT, CAPACITOR, PASSIVE, CERAMIC, MLCC")
    (attr smd)
    (fp_text reference "C63" (at 17.309 7.567 180) (layer "B.SilkS")
        (effects (font (size 0.7 0.7) (thickness 0.15)) (justify left bottom mirror))
    )
    (fp_text value "C_1u_0402" (at -1.022927 -2.155213 180) (layer "B.Fab")
        (effects (font (size 0.7 0.7) (thickness 0.15)) (justify left bottom mirror))
    )
    (fp_text user "License: Apache-2.0" (at -0.939 -5.799 180) (layer "B.Fab") hide
        (effects (font (size 0.7 0.7) (thickness 0.15)) (justify left bottom mirror))
    )
    (fp_text user "${REFERENCE}" (at -0.939 -4.599 180) (layer "B.Fab") hide
        (effects (font (size 0.7 0.7) (thickness 0.15)) (justify left bottom mirror))
    )
    (fp_text user "Author: Antmicro" (at -0.939 -3.399 180) (layer "B.Fab") hide
        (effects (font (size 0.7 0.7) (thickness 0.15)) (justify left bottom mirror))
    )
    (fp_rect (start -0.925 0.47) (end 0.925 -0.47)
      (stroke (width 0.05) (type default)) (fill none) (layer "B.CrtYd"))
    (fp_line (start -0.494 -0.248) (end -0.494 0.25)
      (stroke (width 0.15) (type solid)) (layer "B.Fab"))
    (fp_line (start -0.494 0.25) (end 0.504 0.25)
      (stroke (width 0.15) (type solid)) (layer "B.Fab"))
    (fp_line (start 0.504 -0.248) (end -0.494 -0.248)
      (stroke (width 0.15) (type solid)) (layer "B.Fab"))
    (fp_line (start 0.504 0.25) (end 0.504 -0.248)
      (stroke (width 0.15) (type solid)) (layer "B.Fab"))
    (pad "1" smd roundrect (at -0.48 0) (size 0.59 0.64) (layers "B.Cu" "B.Paste" "B.Mask") (roundrect_rratio 0.25)
      (net 1 "GND") (pintype "passive"))
    (pad "2" smd roundrect (at 0.48 0) (size 0.59 0.64) (layers "B.Cu" "B.Paste" "B.Mask") (roundrect_rratio 0.25)
      (net 107 "Net-(C54-Pad2)") (pintype "passive"))
  )
	(footprint "antmicro-footprints:C_0402_1005Metric" (layer "B.Cu")
    (at 131.5 92.65 -90)
    (descr "Capacitor SMD 0402")
    (tags "capacitor SMD 0402")
    (property "Author" "Antmicro")
    (property "Dielectric" "")
    (property "License" "Apache-2.0")
    (property "MPN" "CC0402KRX5R6BB224")
    (property "Manufacturer" "YAGEO")
    (property "Sheetfile" "tb.kicad_sch")
    (property "Sheetname" "TB Controller")
    (property "Val" "220n")
    (property "Voltage" "")
    (property "ki_description" "SMD Multilayer Ceramic Capacitor, 0.22 µF, 10 V, 0402 [1005 Metric], ± 10%, X5R, CC Series")
    (property "ki_keywords" "0402, SMT, CAPACITOR, PASSIVE, MLCC, CERAMIC")
    (attr smd)
    (fp_text reference "C110" (at -3.877 -0.47 90) (layer "B.SilkS")
        (effects (font (size 0.7 0.7) (thickness 0.15)) (justify left bottom mirror))
    )
    (fp_text value "C_220n_0402" (at -1.022927 -2.155213 90) (layer "B.Fab")
        (effects (font (size 0.7 0.7) (thickness 0.15)) (justify left bottom mirror))
    )
    (fp_text user "License: Apache-2.0" (at -0.939 -5.799 90) (layer "B.Fab") hide
        (effects (font (size 0.7 0.7) (thickness 0.15)) (justify left bottom mirror))
    )
    (fp_text user "${REFERENCE}" (at -0.939 -4.599 90) (layer "B.Fab") hide
        (effects (font (size 0.7 0.7) (thickness 0.15)) (justify left bottom mirror))
    )
    (fp_text user "Author: Antmicro" (at -0.939 -3.399 90) (layer "B.Fab") hide
        (effects (font (size 0.7 0.7) (thickness 0.15)) (justify left bottom mirror))
    )
    (fp_rect (start -0.925 0.47) (end 0.925 -0.47)
      (stroke (width 0.05) (type default)) (fill none) (layer "B.CrtYd"))
    (fp_line (start -0.494 -0.248) (end -0.494 0.25)
      (stroke (width 0.15) (type solid)) (layer "B.Fab"))
    (fp_line (start -0.494 0.25) (end 0.504 0.25)
      (stroke (width 0.15) (type solid)) (layer "B.Fab"))
    (fp_line (start 0.504 -0.248) (end -0.494 -0.248)
      (stroke (width 0.15) (type solid)) (layer "B.Fab"))
    (fp_line (start 0.504 0.25) (end 0.504 -0.248)
      (stroke (width 0.15) (type solid)) (layer "B.Fab"))
    (pad "1" smd roundrect (at -0.48 0 270) (size 0.59 0.64) (layers "B.Cu" "B.Paste" "B.Mask") (roundrect_rratio 0.25)
      (net 81 "/TB Controller/TX1_P") (pintype "passive"))
    (pad "2" smd roundrect (at 0.48 0 270) (size 0.59 0.64) (layers "B.Cu" "B.Paste" "B.Mask") (roundrect_rratio 0.25)
      (net 29 "PCIE_TX1_P") (pintype "passive"))
  )
	(footprint "antmicro-footprints:R_0402_1005Metric" (layer "B.Cu")
    (at 110.065001 86.17 -90)
    (descr "Resistor SMD 0402")
    (tags "resistor SMD 0402")
    (property "Author" "Antmicro")
    (property "Current" "1A")
    (property "License" "Apache-2.0")
    (property "MPN" "ERJ2GE0R00X")
    (property "Manufacturer" "Panasonic")
    (property "Sheetfile" "power.kicad_sch")
    (property "Sheetname" "Power")
    (property "Tolerance" "")
    (property "Val" "0R")
    (property "ki_description" "SMD Chip Resistor, Jumper, 0 ohm, 100 mW, 0402 [1005 Metric], Thick Film, General Purpose")
    (property "ki_keywords" "0402, SMT, RESISTOR, PASSIVE")
    (attr smd)
    (fp_text reference "R12" (at 0.825 -0.424999 90) (layer "B.SilkS")
        (effects (font (size 0.7 0.7) (thickness 0.15)) (justify left bottom mirror))
    )
    (fp_text value "R_0R_0402" (at -1.011843 -1.772047 90) (layer "B.Fab")
        (effects (font (size 0.7 0.7) (thickness 0.15)) (justify left bottom mirror))
    )
    (fp_text user "License: Apache-2.0" (at -0.95 -5.169 90) (layer "B.Fab") hide
        (effects (font (size 0.7 0.7) (thickness 0.15)) (justify left bottom mirror))
    )
    (fp_text user "Author: Antmicro" (at -0.95 -4.169 90) (layer "B.Fab") hide
        (effects (font (size 0.7 0.7) (thickness 0.15)) (justify left bottom mirror))
    )
    (fp_text user "${REFERENCE}" (at -0.95 -3.168 90) (layer "B.Fab") hide
        (effects (font (size 0.7 0.7) (thickness 0.15)) (justify left bottom mirror))
    )
    (fp_rect (start -0.925 0.47) (end 0.925 -0.47)
      (stroke (width 0.05) (type default)) (fill none) (layer "B.CrtYd"))
    (fp_rect (start -0.5 0.25) (end 0.5 -0.25)
      (stroke (width 0.15) (type solid)) (fill none) (layer "B.Fab"))
    (pad "1" smd roundrect (at -0.48 0 270) (size 0.59 0.64) (layers "B.Cu" "B.Paste" "B.Mask") (roundrect_rratio 0.25)
      (net 5 "Net-(U1-VREF)") (pintype "passive"))
    (pad "2" smd roundrect (at 0.48 0 270) (size 0.59 0.64) (layers "B.Cu" "B.Paste" "B.Mask") (roundrect_rratio 0.25)
      (net 147 "Net-(U1-CTRL)") (pintype "passive"))
  )
	(footprint "antmicro-footprints:C_0402_1005Metric" (layer "B.Cu")
    (at 134.8 77.9)
    (descr "Capacitor SMD 0402")
    (tags "capacitor SMD 0402")
    (property "Author" "Antmicro")
    (property "Dielectric" "")
    (property "License" "Apache-2.0")
    (property "MPN" "C1005X6S1A105K050BC")
    (property "Manufacturer" "TDK")
    (property "Sheetfile" "tb-power.kicad_sch")
    (property "Sheetname" "Thunderbolt Controller - Power")
    (property "Val" "1u")
    (property "Voltage" "")
    (property "ki_description" "SMD Multilayer Ceramic Capacitor, 1 µF, 10 V, 0402 [1005 Metric], ± 10%, X6S, C")
    (property "ki_keywords" "0402, SMT, CAPACITOR, PASSIVE, CERAMIC, MLCC")
    (attr smd)
    (fp_text reference "C64" (at 17.6 7.571 180) (layer "B.SilkS")
        (effects (font (size 0.7 0.7) (thickness 0.15)) (justify left bottom mirror))
    )
    (fp_text value "C_1u_0402" (at -1.022927 -2.155213 180) (layer "B.Fab")
        (effects (font (size 0.7 0.7) (thickness 0.15)) (justify left bottom mirror))
    )
    (fp_text user "License: Apache-2.0" (at -0.939 -5.799 180) (layer "B.Fab") hide
        (effects (font (size 0.7 0.7) (thickness 0.15)) (justify left bottom mirror))
    )
    (fp_text user "${REFERENCE}" (at -0.939 -4.599 180) (layer "B.Fab") hide
        (effects (font (size 0.7 0.7) (thickness 0.15)) (justify left bottom mirror))
    )
    (fp_text user "Author: Antmicro" (at -0.939 -3.399 180) (layer "B.Fab") hide
        (effects (font (size 0.7 0.7) (thickness 0.15)) (justify left bottom mirror))
    )
    (fp_rect (start -0.925 0.47) (end 0.925 -0.47)
      (stroke (width 0.05) (type default)) (fill none) (layer "B.CrtYd"))
    (fp_line (start -0.494 -0.248) (end -0.494 0.25)
      (stroke (width 0.15) (type solid)) (layer "B.Fab"))
    (fp_line (start -0.494 0.25) (end 0.504 0.25)
      (stroke (width 0.15) (type solid)) (layer "B.Fab"))
    (fp_line (start 0.504 -0.248) (end -0.494 -0.248)
      (stroke (width 0.15) (type solid)) (layer "B.Fab"))
    (fp_line (start 0.504 0.25) (end 0.504 -0.248)
      (stroke (width 0.15) (type solid)) (layer "B.Fab"))
    (pad "1" smd roundrect (at -0.48 0) (size 0.59 0.64) (layers "B.Cu" "B.Paste" "B.Mask") (roundrect_rratio 0.25)
      (net 1 "GND") (pintype "passive"))
    (pad "2" smd roundrect (at 0.48 0) (size 0.59 0.64) (layers "B.Cu" "B.Paste" "B.Mask") (roundrect_rratio 0.25)
      (net 106 "Net-(C53-Pad2)") (pintype "passive"))
  )
)
